# T6G (Grand Teton) — schematic netlist excerpt (pin names and nets, part order shuffled) for the footprints in the layout excerpt that follows; sources: Cadence DE-HDL packaged netlist, KiCad conversion of 04192023_DAF0TMB3IC0_F0TG_MB_C_brd_V02_OCP.brd

PR6543  Q_RES  0 5% CHIP  pkg 0402LF  page 364 : A = NC_P0V9_RETIMER_CPU1_IMON7 ; B = GND
R6302  Q_RES  200K 1% CHIP  pkg 0402LF  page 178 : A = USB_HUB2_MRP_CFG_BC_EN ; B = GND

(kicad_pcb
	(version 20260206)
	(generator "pcbnew")
	(generator_version "10.0")
	(general
		(thickness 1.6)
		(legacy_teardrops no)
	)
	(paper "A4")
	(title_block
		(title "04192023_DAF0TMB3IC0_F0TG_MB_C_brd_V02_OCP.brd")
		(comment 1 "Grand Teton / footprints 608-609 of 8354")
	)
	(layers
		(0 "F.Cu" signal "TOP")
		(4 "In1.Cu" signal "GND")
		(6 "In2.Cu" signal "IN1")
		(8 "In3.Cu" signal "GND1")
		(10 "In4.Cu" signal "IN2")
		(12 "In5.Cu" signal "GND2")
		(14 "In6.Cu" signal "IN3")
		(16 "In7.Cu" signal "GND3")
		(18 "In8.Cu" signal "VCC")
		(20 "In9.Cu" signal "VCC1")
		(22 "In10.Cu" signal "GND4")
		(24 "In11.Cu" signal "IN4")
		(26 "In12.Cu" signal "GND5")
		(28 "In13.Cu" signal "IN5")
		(30 "In14.Cu" signal "GND6")
		(32 "In15.Cu" signal "IN6")
		(34 "In16.Cu" signal "GND7")
		(2 "B.Cu" signal "BOTTOM")
		(9 "F.Adhes" user "F.Adhesive")
		(11 "B.Adhes" user "B.Adhesive")
		(13 "F.Paste" user "Package Geometry/Pastemask Top")
		(15 "B.Paste" user "Package Geometry/Pastemask Bottom")
		(5 "F.SilkS" user "Ref Des/Silkscreen Top")
		(7 "B.SilkS" user "Ref Des/Silkscreen Bottom")
		(1 "F.Mask" user "Board Geometry/Soldermask Top")
		(3 "B.Mask" user "Board Geometry/Soldermask Bottom")
		(17 "Dwgs.User" user "User.Drawings")
		(19 "Cmts.User" user "User.Comments")
		(21 "Eco1.User" user "User.Eco1")
		(23 "Eco2.User" user "User.Eco2")
		(25 "Edge.Cuts" user "Board Geometry/Outline")
		(27 "Margin" user)
		(31 "F.CrtYd" user "Package Geometry/Place Bound Top")
		(29 "B.CrtYd" user "Package Geometry/Place Bound Bottom")
		(35 "F.Fab" user "Ref Des/Assembly Top")
		(33 "B.Fab" user "Ref Des/Assembly Bottom")
	)
	(footprint ""
		(layer "F.Cu")
		(at 12.987782 -415.263584 90)
		(property "Reference" "PR6543"
			(at 0 0 90)
			(layer "F.SilkS")
			(hide yes)
			(effects
				(font
					(size 1.27 1.27)
				)
			)
		)
		(property "Value" ""
			(at 0 0 90)
			(layer "F.Fab")
			(effects
				(font
					(size 1.27 1.27)
				)
			)
		)
		(duplicate_pad_numbers_are_jumpers no)
		(fp_line
			(start 0.7874 -0.4064)
			(end 0.7874 0.4064)
			(stroke
				(width 0.1524)
				(type default)
			)
			(layer "F.SilkS")
		)
		(fp_line
			(start -0.7874 -0.4064)
			(end 0.7874 -0.4064)
			(stroke
				(width 0.1524)
				(type default)
			)
			(layer "F.SilkS")
		)
		(fp_line
			(start 0.7874 0.4064)
			(end -0.7874 0.4064)
			(stroke
				(width 0.1524)
				(type default)
			)
			(layer "F.SilkS")
		)
		(fp_line
			(start -0.7874 0.4064)
			(end -0.7874 -0.4064)
			(stroke
				(width 0.1524)
				(type default)
			)
			(layer "F.SilkS")
		)
		(fp_line
			(start -0.12065 -0.305054)
			(end -0.12065 -0.2794)
			(stroke
				(width 0.1)
				(type default)
			)
			(layer "F.Fab")
		)
		(fp_line
			(start -0.67945 -0.305054)
			(end -0.12065 -0.305054)
			(stroke
				(width 0.1)
				(type default)
			)
			(layer "F.Fab")
		)
		(fp_line
			(start 0.67945 -0.3048)
			(end 0.67945 0.3048)
			(stroke
				(width 0.1)
				(type default)
			)
			(layer "F.Fab")
		)
		(fp_line
			(start 0.12065 -0.3048)
			(end 0.67945 -0.3048)
			(stroke
				(width 0.1)
				(type default)
			)
			(layer "F.Fab")
		)
		(fp_line
			(start 0.12065 -0.2794)
			(end 0.12065 -0.3048)
			(stroke
				(width 0.1)
				(type default)
			)
			(layer "F.Fab")
		)
		(fp_line
			(start -0.12065 -0.2794)
			(end 0.12065 -0.2794)
			(stroke
				(width 0.1)
				(type default)
			)
			(layer "F.Fab")
		)
		(fp_line
			(start 0.120396 0.2794)
			(end -0.12065 0.2794)
			(stroke
				(width 0.1)
				(type default)
			)
			(layer "F.Fab")
		)
		(fp_line
			(start -0.12065 0.2794)
			(end -0.12065 0.3048)
			(stroke
				(width 0.1)
				(type default)
			)
			(layer "F.Fab")
		)
		(fp_line
			(start 0.67945 0.3048)
			(end 0.120396 0.3048)
			(stroke
				(width 0.1)
				(type default)
			)
			(layer "F.Fab")
		)
		(fp_line
			(start 0.120396 0.3048)
			(end 0.120396 0.2794)
			(stroke
				(width 0.1)
				(type default)
			)
			(layer "F.Fab")
		)
		(fp_line
			(start -0.12065 0.3048)
			(end -0.67945 0.3048)
			(stroke
				(width 0.1)
				(type default)
			)
			(layer "F.Fab")
		)
		(fp_line
			(start -0.67945 0.3048)
			(end -0.67945 -0.305054)
			(stroke
				(width 0.1)
				(type default)
			)
			(layer "F.Fab")
		)
		(pad "1" smd circle
			(at -0.40005 0 90)
			(size 0 0)
			(layers "F.Cu" "F.Mask" "F.Paste")
			(net "NC_P0V9_RETIMER_CPU1_IMON7")
		)
		(pad "2" smd circle
			(at 0.40005 0 90)
			(size 0 0)
			(layers "F.Cu" "F.Mask" "F.Paste")
			(net "GND")
		)
	)
	(footprint ""
		(layer "F.Cu")
		(at 114.629946 -54.882034 90)
		(property "Reference" "R6302"
			(at 0 0 90)
			(layer "F.SilkS")
			(hide yes)
			(effects
				(font
					(size 1.27 1.27)
				)
			)
		)
		(property "Value" ""
			(at 0 0 90)
			(layer "F.Fab")
			(effects
				(font
					(size 1.27 1.27)
				)
			)
		)
		(duplicate_pad_numbers_are_jumpers no)
		(fp_line
			(start 0.7874 -0.4064)
			(end 0.7874 0.4064)
			(stroke
				(width 0.1524)
				(type default)
			)
			(layer "F.SilkS")
		)
		(fp_line
			(start -0.7874 -0.4064)
			(end 0.7874 -0.4064)
			(stroke
				(width 0.1524)
				(type default)
			)
			(layer "F.SilkS")
		)
		(fp_line
			(start 0.7874 0.4064)
			(end -0.7874 0.4064)
			(stroke
				(width 0.1524)
				(type default)
			)
			(layer "F.SilkS")
		)
		(fp_line
			(start -0.7874 0.4064)
			(end -0.7874 -0.4064)
			(stroke
				(width 0.1524)
				(type default)
			)
			(layer "F.SilkS")
		)
		(fp_line
			(start -0.12065 -0.305054)
			(end -0.12065 -0.2794)
			(stroke
				(width 0.1)
				(type default)
			)
			(layer "F.Fab")
		)
		(fp_line
			(start -0.67945 -0.305054)
			(end -0.12065 -0.305054)
			(stroke
				(width 0.1)
				(type default)
			)
			(layer "F.Fab")
		)
		(fp_line
			(start 0.67945 -0.3048)
			(end 0.67945 0.3048)
			(stroke
				(width 0.1)
				(type default)
			)
			(layer "F.Fab")
		)
		(fp_line
			(start 0.12065 -0.3048)
			(end 0.67945 -0.3048)
			(stroke
				(width 0.1)
				(type default)
			)
			(layer "F.Fab")
		)
		(fp_line
			(start 0.12065 -0.2794)
			(end 0.12065 -0.3048)
			(stroke
				(width 0.1)
				(type default)
			)
			(layer "F.Fab")
		)
		(fp_line
			(start -0.12065 -0.2794)
			(end 0.12065 -0.2794)
			(stroke
				(width 0.1)
				(type default)
			)
			(layer "F.Fab")
		)
		(fp_line
			(start 0.120396 0.2794)
			(end -0.12065 0.2794)
			(stroke
				(width 0.1)
				(type default)
			)
			(layer "F.Fab")
		)
		(fp_line
			(start -0.12065 0.2794)
			(end -0.12065 0.3048)
			(stroke
				(width 0.1)
				(type default)
			)
			(layer "F.Fab")
		)
		(fp_line
			(start 0.67945 0.3048)
			(end 0.120396 0.3048)
			(stroke
				(width 0.1)
				(type default)
			)
			(layer "F.Fab")
		)
		(fp_line
			(start 0.120396 0.3048)
			(end 0.120396 0.2794)
			(stroke
				(width 0.1)
				(type default)
			)
			(layer "F.Fab")
		)
		(fp_line
			(start -0.12065 0.3048)
			(end -0.67945 0.3048)
			(stroke
				(width 0.1)
				(type default)
			)
			(layer "F.Fab")
		)
		(fp_line
			(start -0.67945 0.3048)
			(end -0.67945 -0.305054)
			(stroke
				(width 0.1)
				(type default)
			)
			(layer "F.Fab")
		)
		(pad "1" smd circle
			(at -0.40005 0 90)
			(size 0 0)
			(layers "F.Cu" "F.Mask" "F.Paste")
			(net "USB_HUB2_MRP_CFG_BC_EN")
		)
		(pad "2" smd circle
			(at 0.40005 0 90)
			(size 0 0)
			(layers "F.Cu" "F.Mask" "F.Paste")
			(net "GND")
		)
	)
)
